(kicad_pcb
	(version 20260206)
	(generator "pcbnew")
	(generator_version "10.0")
	(general
		(thickness 1.6)
		(legacy_teardrops no)
	)
	(paper "A4")
	(title_block
		(title "04192023_DAF0TMB3IC0_F0TG_MB_C_brd_V02_OCP.brd")
		(comment 1 "Grand Teton / footprints 6972-6978 of 8354")
	)
	(layers
		(0 "F.Cu" signal "TOP")
		(4 "In1.Cu" signal "GND")
		(6 "In2.Cu" signal "IN1")
		(8 "In3.Cu" signal "GND1")
		(10 "In4.Cu" signal "IN2")
		(12 "In5.Cu" signal "GND2")
		(14 "In6.Cu" signal "IN3")
		(16 "In7.Cu" signal "GND3")
		(18 "In8.Cu" signal "VCC")
		(20 "In9.Cu" signal "VCC1")
		(22 "In10.Cu" signal "GND4")
		(24 "In11.Cu" signal "IN4")
		(26 "In12.Cu" signal "GND5")
		(28 "In13.Cu" signal "IN5")
		(30 "In14.Cu" signal "GND6")
		(32 "In15.Cu" signal "IN6")
		(34 "In16.Cu" signal "GND7")
		(2 "B.Cu" signal "BOTTOM")
		(9 "F.Adhes" user "F.Adhesive")
		(11 "B.Adhes" user "B.Adhesive")
		(13 "F.Paste" user "Package Geometry/Pastemask Top")
		(15 "B.Paste" user "Package Geometry/Pastemask Bottom")
		(5 "F.SilkS" user "Ref Des/Silkscreen Top")
		(7 "B.SilkS" user "Ref Des/Silkscreen Bottom")
		(1 "F.Mask" user "Board Geometry/Soldermask Top")
		(3 "B.Mask" user "Board Geometry/Soldermask Bottom")
		(17 "Dwgs.User" user "User.Drawings")
		(19 "Cmts.User" user "User.Comments")
		(21 "Eco1.User" user "User.Eco1")
		(23 "Eco2.User" user "User.Eco2")
		(25 "Edge.Cuts" user "Board Geometry/Outline")
		(27 "Margin" user)
		(31 "F.CrtYd" user "Package Geometry/Place Bound Top")
		(29 "B.CrtYd" user "Package Geometry/Place Bound Bottom")
		(35 "F.Fab" user "Ref Des/Assembly Top")
		(33 "B.Fab" user "Ref Des/Assembly Bottom")
	)
	(footprint ""
		(layer "B.Cu")
		(at 317.967614 -389.49503)
		(property "Reference" "C7009"
			(at 3.4925 3.131312 0)
			(unlocked yes)
			(layer "B.SilkS")
			(effects
				(font
					(size 0.7874 0.5842)
					(thickness 0.1524)
				)
				(justify left mirror)
			)
		)
		(property "Value" ""
			(at 0 0 0)
			(layer "B.Fab")
			(effects
				(font
					(size 1.27 1.27)
				)
				(justify mirror)
			)
		)
		(duplicate_pad_numbers_are_jumpers no)
		(fp_line
			(start -4.53898 -2.15011)
			(end -4.53898 2.15011)
			(stroke
				(width 0.1524)
				(type default)
			)
			(layer "B.SilkS")
		)
		(fp_line
			(start -4.53898 2.15011)
			(end 4.53898 2.15011)
			(stroke
				(width 0.1524)
				(type default)
			)
			(layer "B.SilkS")
		)
		(fp_line
			(start 4.53898 -2.150618)
			(end 4.539742 2.152142)
			(stroke
				(width 0.1524)
				(type default)
			)
			(layer "B.SilkS")
		)
		(fp_line
			(start 4.53898 -2.15011)
			(end -4.53898 -2.15011)
			(stroke
				(width 0.1524)
				(type default)
			)
			(layer "B.SilkS")
		)
		(fp_line
			(start 4.53898 2.15011)
			(end 4.53898 -2.15011)
			(stroke
				(width 0.1524)
				(type default)
			)
			(layer "B.SilkS")
		)
		(fp_line
			(start 4.69138 -2.150618)
			(end 4.692396 2.161032)
			(stroke
				(width 0.1524)
				(type default)
			)
			(layer "B.SilkS")
		)
		(fp_line
			(start 4.83108 2.150364)
			(end 4.447794 2.149348)
			(stroke
				(width 0.1524)
				(type default)
			)
			(layer "B.SilkS")
		)
		(fp_line
			(start 4.84378 -2.150618)
			(end 4.53898 -2.150618)
			(stroke
				(width 0.1524)
				(type default)
			)
			(layer "B.SilkS")
		)
		(fp_line
			(start 4.84378 -2.150618)
			(end 4.842256 2.163064)
			(stroke
				(width 0.1524)
				(type default)
			)
			(layer "B.SilkS")
		)
		(fp_line
			(start -3.64998 -2.15011)
			(end -3.64998 2.15011)
			(stroke
				(width 0.1)
				(type default)
			)
			(layer "B.Fab")
		)
		(fp_line
			(start -3.64998 2.15011)
			(end 3.64998 2.15011)
			(stroke
				(width 0.1)
				(type default)
			)
			(layer "B.Fab")
		)
		(fp_line
			(start 3.64998 -2.15011)
			(end -3.64998 -2.15011)
			(stroke
				(width 0.1)
				(type default)
			)
			(layer "B.Fab")
		)
		(fp_line
			(start 3.64998 2.15011)
			(end 3.64998 -2.15011)
			(stroke
				(width 0.1)
				(type default)
			)
			(layer "B.Fab")
		)
		(fp_text user "-"
			(at -3.109214 2.382012 0)
			(unlocked yes)
			(layer "B.SilkS")
			(effects
				(font
					(size 1.905 1.4224)
					(thickness 0.1524)
				)
				(justify left mirror)
			)
		)
		(fp_text user "+"
			(at 6.214872 -0.337058 0)
			(unlocked yes)
			(layer "B.SilkS")
			(effects
				(font
					(size 1.905 1.4224)
					(thickness 0.1524)
				)
				(justify left mirror)
			)
		)
		(fp_text user "-"
			(at -4.313174 -0.094488 0)
			(unlocked yes)
			(layer "B.Fab")
			(effects
				(font
					(size 1.905 1.4224)
					(thickness 0.1524)
				)
				(justify left mirror)
			)
		)
		(fp_text user "+"
			(at 6.214872 -0.337058 0)
			(unlocked yes)
			(layer "B.Fab")
			(effects
				(font
					(size 1.905 1.4224)
					(thickness 0.1524)
				)
				(justify left mirror)
			)
		)
		(pad "1" smd rect
			(at 3.199892 0 180)
			(size 2.413 2.8194)
			(layers "B.Cu" "B.Mask" "B.Paste")
			(net "P0V9_CPU0_RT0_2A")
		)
		(pad "2" smd rect
			(at -3.199892 0 180)
			(size 2.413 2.8194)
			(layers "B.Cu" "B.Mask" "B.Paste")
			(net "GND")
		)
	)
	(footprint ""
		(layer "B.Cu")
		(at 121.706386 -254.194564)
		(property "Reference" "C2472"
			(at 0 0 0)
			(layer "B.SilkS")
			(hide yes)
			(effects
				(font
					(size 1.27 1.27)
				)
				(justify mirror)
			)
		)
		(property "Value" ""
			(at 0 0 0)
			(layer "B.Fab")
			(effects
				(font
					(size 1.27 1.27)
				)
				(justify mirror)
			)
		)
		(duplicate_pad_numbers_are_jumpers no)
		(fp_line
			(start -0.7874 -0.4064)
			(end -0.7874 0.4064)
			(stroke
				(width 0.1524)
				(type default)
			)
			(layer "B.SilkS")
		)
		(fp_line
			(start -0.7874 0.4064)
			(end 0.7874 0.4064)
			(stroke
				(width 0.1524)
				(type default)
			)
			(layer "B.SilkS")
		)
		(fp_line
			(start 0.7874 -0.4064)
			(end -0.7874 -0.4064)
			(stroke
				(width 0.1524)
				(type default)
			)
			(layer "B.SilkS")
		)
		(fp_line
			(start 0.7874 0.4064)
			(end 0.7874 -0.4064)
			(stroke
				(width 0.1524)
				(type default)
			)
			(layer "B.SilkS")
		)
		(fp_line
			(start -0.67945 -0.3048)
			(end -0.67945 0.3048)
			(stroke
				(width 0.1)
				(type default)
			)
			(layer "B.Fab")
		)
		(fp_line
			(start -0.67945 0.3048)
			(end -0.120396 0.3048)
			(stroke
				(width 0.1)
				(type default)
			)
			(layer "B.Fab")
		)
		(fp_line
			(start -0.12065 -0.3048)
			(end -0.67945 -0.3048)
			(stroke
				(width 0.1)
				(type default)
			)
			(layer "B.Fab")
		)
		(fp_line
			(start -0.12065 -0.2794)
			(end -0.12065 -0.3048)
			(stroke
				(width 0.1)
				(type default)
			)
			(layer "B.Fab")
		)
		(fp_line
			(start -0.120396 0.2794)
			(end 0.12065 0.2794)
			(stroke
				(width 0.1)
				(type default)
			)
			(layer "B.Fab")
		)
		(fp_line
			(start -0.120396 0.3048)
			(end -0.120396 0.2794)
			(stroke
				(width 0.1)
				(type default)
			)
			(layer "B.Fab")
		)
		(fp_line
			(start 0.12065 -0.305054)
			(end 0.12065 -0.2794)
			(stroke
				(width 0.1)
				(type default)
			)
			(layer "B.Fab")
		)
		(fp_line
			(start 0.12065 -0.2794)
			(end -0.12065 -0.2794)
			(stroke
				(width 0.1)
				(type default)
			)
			(layer "B.Fab")
		)
		(fp_line
			(start 0.12065 0.2794)
			(end 0.12065 0.3048)
			(stroke
				(width 0.1)
				(type default)
			)
			(layer "B.Fab")
		)
		(fp_line
			(start 0.12065 0.3048)
			(end 0.67945 0.3048)
			(stroke
				(width 0.1)
				(type default)
			)
			(layer "B.Fab")
		)
		(fp_line
			(start 0.67945 -0.305054)
			(end 0.12065 -0.305054)
			(stroke
				(width 0.1)
				(type default)
			)
			(layer "B.Fab")
		)
		(fp_line
			(start 0.67945 0.3048)
			(end 0.67945 -0.305054)
			(stroke
				(width 0.1)
				(type default)
			)
			(layer "B.Fab")
		)
		(pad "1" smd circle
			(at 0.40005 0 180)
			(size 0 0)
			(layers "B.Cu" "B.Mask" "B.Paste")
			(net "PVDDCR_SOC_P1")
		)
		(pad "2" smd circle
			(at -0.40005 0 180)
			(size 0 0)
			(layers "B.Cu" "B.Mask" "B.Paste")
			(net "GND")
		)
	)
	(footprint ""
		(layer "B.Cu")
		(at 149.419056 -390.560052 90)
		(property "Reference" "C406"
			(at 0 0 90)
			(layer "B.SilkS")
			(hide yes)
			(effects
				(font
					(size 1.27 1.27)
				)
				(justify mirror)
			)
		)
		(property "Value" ""
			(at 0 0 90)
			(layer "B.Fab")
			(effects
				(font
					(size 1.27 1.27)
				)
				(justify mirror)
			)
		)
		(duplicate_pad_numbers_are_jumpers no)
		(fp_line
			(start 0.7874 -0.4064)
			(end -0.7874 -0.4064)
			(stroke
				(width 0.1524)
				(type default)
			)
			(layer "B.SilkS")
		)
		(fp_line
			(start -0.7874 -0.4064)
			(end -0.7874 0.4064)
			(stroke
				(width 0.1524)
				(type default)
			)
			(layer "B.SilkS")
		)
		(fp_line
			(start 0.7874 0.4064)
			(end 0.7874 -0.4064)
			(stroke
				(width 0.1524)
				(type default)
			)
			(layer "B.SilkS")
		)
		(fp_line
			(start -0.7874 0.4064)
			(end 0.7874 0.4064)
			(stroke
				(width 0.1524)
				(type default)
			)
			(layer "B.SilkS")
		)
		(fp_line
			(start 0.67945 -0.305054)
			(end 0.12065 -0.305054)
			(stroke
				(width 0.1)
				(type default)
			)
			(layer "B.Fab")
		)
		(fp_line
			(start 0.12065 -0.305054)
			(end 0.12065 -0.2794)
			(stroke
				(width 0.1)
				(type default)
			)
			(layer "B.Fab")
		)
		(fp_line
			(start -0.12065 -0.3048)
			(end -0.67945 -0.3048)
			(stroke
				(width 0.1)
				(type default)
			)
			(layer "B.Fab")
		)
		(fp_line
			(start -0.67945 -0.3048)
			(end -0.67945 0.3048)
			(stroke
				(width 0.1)
				(type default)
			)
			(layer "B.Fab")
		)
		(fp_line
			(start 0.12065 -0.2794)
			(end -0.12065 -0.2794)
			(stroke
				(width 0.1)
				(type default)
			)
			(layer "B.Fab")
		)
		(fp_line
			(start -0.12065 -0.2794)
			(end -0.12065 -0.3048)
			(stroke
				(width 0.1)
				(type default)
			)
			(layer "B.Fab")
		)
		(fp_line
			(start 0.12065 0.2794)
			(end 0.12065 0.3048)
			(stroke
				(width 0.1)
				(type default)
			)
			(layer "B.Fab")
		)
		(fp_line
			(start -0.120396 0.2794)
			(end 0.12065 0.2794)
			(stroke
				(width 0.1)
				(type default)
			)
			(layer "B.Fab")
		)
		(fp_line
			(start 0.67945 0.3048)
			(end 0.67945 -0.305054)
			(stroke
				(width 0.1)
				(type default)
			)
			(layer "B.Fab")
		)
		(fp_line
			(start 0.12065 0.3048)
			(end 0.67945 0.3048)
			(stroke
				(width 0.1)
				(type default)
			)
			(layer "B.Fab")
		)
		(fp_line
			(start -0.120396 0.3048)
			(end -0.120396 0.2794)
			(stroke
				(width 0.1)
				(type default)
			)
			(layer "B.Fab")
		)
		(fp_line
			(start -0.67945 0.3048)
			(end -0.120396 0.3048)
			(stroke
				(width 0.1)
				(type default)
			)
			(layer "B.Fab")
		)
		(pad "1" smd circle
			(at 0.40005 0 270)
			(size 0 0)
			(layers "B.Cu" "B.Mask" "B.Paste")
			(net "P0V9_CPU1_RT2_2A")
		)
		(pad "2" smd circle
			(at -0.40005 0 270)
			(size 0 0)
			(layers "B.Cu" "B.Mask" "B.Paste")
			(net "GND")
		)
	)
	(footprint ""
		(layer "B.Cu")
		(at 169.686732 -435.851808 90)
		(property "Reference" "R4126"
			(at 0 0 90)
			(layer "B.SilkS")
			(hide yes)
			(effects
				(font
					(size 1.27 1.27)
				)
				(justify mirror)
			)
		)
		(property "Value" ""
			(at 0 0 90)
			(layer "B.Fab")
			(effects
				(font
					(size 1.27 1.27)
				)
				(justify mirror)
			)
		)
		(duplicate_pad_numbers_are_jumpers no)
		(fp_line
			(start 0.7874 -0.4064)
			(end -0.7874 -0.4064)
			(stroke
				(width 0.1524)
				(type default)
			)
			(layer "B.SilkS")
		)
		(fp_line
			(start -0.7874 -0.4064)
			(end -0.7874 0.4064)
			(stroke
				(width 0.1524)
				(type default)
			)
			(layer "B.SilkS")
		)
		(fp_line
			(start 0.7874 0.4064)
			(end 0.7874 -0.4064)
			(stroke
				(width 0.1524)
				(type default)
			)
			(layer "B.SilkS")
		)
		(fp_line
			(start -0.7874 0.4064)
			(end 0.7874 0.4064)
			(stroke
				(width 0.1524)
				(type default)
			)
			(layer "B.SilkS")
		)
		(fp_line
			(start 0.67945 -0.305054)
			(end 0.12065 -0.305054)
			(stroke
				(width 0.1)
				(type default)
			)
			(layer "B.Fab")
		)
		(fp_line
			(start 0.12065 -0.305054)
			(end 0.12065 -0.2794)
			(stroke
				(width 0.1)
				(type default)
			)
			(layer "B.Fab")
		)
		(fp_line
			(start -0.12065 -0.3048)
			(end -0.67945 -0.3048)
			(stroke
				(width 0.1)
				(type default)
			)
			(layer "B.Fab")
		)
		(fp_line
			(start -0.67945 -0.3048)
			(end -0.67945 0.3048)
			(stroke
				(width 0.1)
				(type default)
			)
			(layer "B.Fab")
		)
		(fp_line
			(start 0.12065 -0.2794)
			(end -0.12065 -0.2794)
			(stroke
				(width 0.1)
				(type default)
			)
			(layer "B.Fab")
		)
		(fp_line
			(start -0.12065 -0.2794)
			(end -0.12065 -0.3048)
			(stroke
				(width 0.1)
				(type default)
			)
			(layer "B.Fab")
		)
		(fp_line
			(start 0.12065 0.2794)
			(end 0.12065 0.3048)
			(stroke
				(width 0.1)
				(type default)
			)
			(layer "B.Fab")
		)
		(fp_line
			(start -0.120396 0.2794)
			(end 0.12065 0.2794)
			(stroke
				(width 0.1)
				(type default)
			)
			(layer "B.Fab")
		)
		(fp_line
			(start 0.67945 0.3048)
			(end 0.67945 -0.305054)
			(stroke
				(width 0.1)
				(type default)
			)
			(layer "B.Fab")
		)
		(fp_line
			(start 0.12065 0.3048)
			(end 0.67945 0.3048)
			(stroke
				(width 0.1)
				(type default)
			)
			(layer "B.Fab")
		)
		(fp_line
			(start -0.120396 0.3048)
			(end -0.120396 0.2794)
			(stroke
				(width 0.1)
				(type default)
			)
			(layer "B.Fab")
		)
		(fp_line
			(start -0.67945 0.3048)
			(end -0.120396 0.3048)
			(stroke
				(width 0.1)
				(type default)
			)
			(layer "B.Fab")
		)
		(pad "1" smd circle
			(at 0.40005 0 270)
			(size 0 0)
			(layers "B.Cu" "B.Mask" "B.Paste")
			(net "P3V3_AUX")
		)
		(pad "2" smd circle
			(at -0.40005 0 270)
			(size 0 0)
			(layers "B.Cu" "B.Mask" "B.Paste")
			(net "PRSNT_CABLE_GPU_B3")
		)
	)
	(footprint ""
		(layer "B.Cu")
		(at 344.306144 -395.148562 90)
		(property "Reference" "C603"
			(at 0 0 90)
			(layer "B.SilkS")
			(hide yes)
			(effects
				(font
					(size 1.27 1.27)
				)
				(justify mirror)
			)
		)
		(property "Value" ""
			(at 0 0 90)
			(layer "B.Fab")
			(effects
				(font
					(size 1.27 1.27)
				)
				(justify mirror)
			)
		)
		(duplicate_pad_numbers_are_jumpers no)
		(fp_line
			(start 0.299974 -0.150114)
			(end -0.299974 -0.150114)
			(stroke
				(width 0.1)
				(type default)
			)
			(layer "B.Fab")
		)
		(fp_line
			(start -0.299974 -0.150114)
			(end -0.299974 0.150114)
			(stroke
				(width 0.1)
				(type default)
			)
			(layer "B.Fab")
		)
		(fp_line
			(start 0.299974 0.150114)
			(end 0.299974 -0.150114)
			(stroke
				(width 0.1)
				(type default)
			)
			(layer "B.Fab")
		)
		(fp_line
			(start -0.299974 0.150114)
			(end 0.299974 0.150114)
			(stroke
				(width 0.1)
				(type default)
			)
			(layer "B.Fab")
		)
		(pad "1" smd rect
			(at 0.2667 0 270)
			(size 0.3048 0.381)
			(layers "B.Cu" "B.Mask" "B.Paste")
			(net "P1V8_CPU0_RT1_1A")
		)
		(pad "2" smd rect
			(at -0.2667 0 270)
			(size 0.3048 0.381)
			(layers "B.Cu" "B.Mask" "B.Paste")
			(net "GND")
		)
	)
	(footprint ""
		(layer "B.Cu")
		(at 404.922736 -164.804852 90)
		(property "Reference" "PC588_2"
			(at 0 0 90)
			(layer "B.SilkS")
			(hide yes)
			(effects
				(font
					(size 1.27 1.27)
				)
				(justify mirror)
			)
		)
		(property "Value" ""
			(at 0 0 90)
			(layer "B.Fab")
			(effects
				(font
					(size 1.27 1.27)
				)
				(justify mirror)
			)
		)
		(duplicate_pad_numbers_are_jumpers no)
		(fp_line
			(start 1.524 -0.762)
			(end -1.524 -0.762)
			(stroke
				(width 0.1524)
				(type default)
			)
			(layer "B.SilkS")
		)
		(fp_line
			(start -1.524 -0.762)
			(end -1.524 0.762)
			(stroke
				(width 0.1524)
				(type default)
			)
			(layer "B.SilkS")
		)
		(fp_line
			(start 1.524 0.762)
			(end 1.524 -0.762)
			(stroke
				(width 0.1524)
				(type default)
			)
			(layer "B.SilkS")
		)
		(fp_line
			(start -1.524 0.762)
			(end 1.524 0.762)
			(stroke
				(width 0.1524)
				(type default)
			)
			(layer "B.SilkS")
		)
		(fp_line
			(start 1.1049 -0.724916)
			(end 1.1049 0.724916)
			(stroke
				(width 0.1)
				(type default)
			)
			(layer "B.Fab")
		)
		(fp_line
			(start -1.1049 -0.724916)
			(end 1.1049 -0.724916)
			(stroke
				(width 0.1)
				(type default)
			)
			(layer "B.Fab")
		)
		(fp_line
			(start 1.1049 0.724916)
			(end -1.1049 0.724916)
			(stroke
				(width 0.1)
				(type default)
			)
			(layer "B.Fab")
		)
		(fp_line
			(start -1.1049 0.724916)
			(end -1.1049 -0.724916)
			(stroke
				(width 0.1)
				(type default)
			)
			(layer "B.Fab")
		)
		(pad "1" smd rect
			(at 0.889 0 90)
			(size 1.016 1.27)
			(layers "B.Cu" "B.Mask" "B.Paste")
			(net "SW_P12V_AUX_PVDDCR_SOC_P0_FLT")
		)
		(pad "2" smd rect
			(at -0.889 0 90)
			(size 1.016 1.27)
			(layers "B.Cu" "B.Mask" "B.Paste")
			(net "GND")
		)
	)
	(footprint ""
		(layer "B.Cu")
		(at 138.65352 -37.717222 180)
		(property "Reference" "C6056"
			(at 0 0 0)
			(layer "B.SilkS")
			(hide yes)
			(effects
				(font
					(size 1.27 1.27)
				)
				(justify mirror)
			)
		)
		(property "Value" ""
			(at 0 0 0)
			(layer "B.Fab")
			(effects
				(font
					(size 1.27 1.27)
				)
				(justify mirror)
			)
		)
		(duplicate_pad_numbers_are_jumpers no)
		(fp_line
			(start 0.7874 0.4064)
			(end 0.7874 -0.4064)
			(stroke
				(width 0.1524)
				(type default)
			)
			(layer "B.SilkS")
		)
		(fp_line
			(start 0.7874 -0.4064)
			(end -0.7874 -0.4064)
			(stroke
				(width 0.1524)
				(type default)
			)
			(layer "B.SilkS")
		)
		(fp_line
			(start -0.7874 0.4064)
			(end 0.7874 0.4064)
			(stroke
				(width 0.1524)
				(type default)
			)
			(layer "B.SilkS")
		)
		(fp_line
			(start -0.7874 -0.4064)
			(end -0.7874 0.4064)
			(stroke
				(width 0.1524)
				(type default)
			)
			(layer "B.SilkS")
		)
		(fp_line
			(start 0.67945 0.3048)
			(end 0.67945 -0.305054)
			(stroke
				(width 0.1)
				(type default)
			)
			(layer "B.Fab")
		)
		(fp_line
			(start 0.67945 -0.305054)
			(end 0.12065 -0.305054)
			(stroke
				(width 0.1)
				(type default)
			)
			(layer "B.Fab")
		)
		(fp_line
			(start 0.12065 0.3048)
			(end 0.67945 0.3048)
			(stroke
				(width 0.1)
				(type default)
			)
			(layer "B.Fab")
		)
		(fp_line
			(start 0.12065 0.2794)
			(end 0.12065 0.3048)
			(stroke
				(width 0.1)
				(type default)
			)
			(layer "B.Fab")
		)
		(fp_line
			(start 0.12065 -0.2794)
			(end -0.12065 -0.2794)
			(stroke
				(width 0.1)
				(type default)
			)
			(layer "B.Fab")
		)
		(fp_line
			(start 0.12065 -0.305054)
			(end 0.12065 -0.2794)
			(stroke
				(width 0.1)
				(type default)
			)
			(layer "B.Fab")
		)
		(fp_line
			(start -0.120396 0.3048)
			(end -0.120396 0.2794)
			(stroke
				(width 0.1)
				(type default)
			)
			(layer "B.Fab")
		)
		(fp_line
			(start -0.120396 0.2794)
			(end 0.12065 0.2794)
			(stroke
				(width 0.1)
				(type default)
			)
			(layer "B.Fab")
		)
		(fp_line
			(start -0.12065 -0.2794)
			(end -0.12065 -0.3048)
			(stroke
				(width 0.1)
				(type default)
			)
			(layer "B.Fab")
		)
		(fp_line
			(start -0.12065 -0.3048)
			(end -0.67945 -0.3048)
			(stroke
				(width 0.1)
				(type default)
			)
			(layer "B.Fab")
		)
		(fp_line
			(start -0.67945 0.3048)
			(end -0.120396 0.3048)
			(stroke
				(width 0.1)
				(type default)
			)
			(layer "B.Fab")
		)
		(fp_line
			(start -0.67945 -0.3048)
			(end -0.67945 0.3048)
			(stroke
				(width 0.1)
				(type default)
			)
			(layer "B.Fab")
		)
		(pad "1" smd circle
			(at 0.40005 0)
			(size 0 0)
			(layers "B.Cu" "B.Mask" "B.Paste")
			(net "P1V2_AUX")
		)
		(pad "2" smd circle
			(at -0.40005 0)
			(size 0 0)
			(layers "B.Cu" "B.Mask" "B.Paste")
			(net "GND")
		)
	)
)
